(kicad_pcb
	(version 20260206)
	(generator "pcbnew")
	(generator_version "10.0")
	(general
		(thickness 1.6)
		(legacy_teardrops no)
	)
	(paper "A4")
	(title_block
		(title "Bryce Canyon_IOM_IOC_16318-2_OCP.brd")
		(comment 1 "Bryce Canyon / footprints 439-445 of 1605")
	)
	(layers
		(0 "F.Cu" signal "TOP")
		(4 "In1.Cu" signal "L2GND")
		(6 "In2.Cu" signal "L3")
		(8 "In3.Cu" signal "L4VCC")
		(10 "In4.Cu" signal "L5VCC")
		(12 "In5.Cu" signal "L6")
		(14 "In6.Cu" signal "L7GND")
		(2 "B.Cu" signal "BOTTOM")
		(9 "F.Adhes" user "F.Adhesive")
		(11 "B.Adhes" user "B.Adhesive")
		(13 "F.Paste" user "Package Geometry/Pastemask Top")
		(15 "B.Paste" user "Package Geometry/Pastemask Bottom")
		(5 "F.SilkS" user "Ref Des/Silkscreen Top")
		(7 "B.SilkS" user "Ref Des/Silkscreen Bottom")
		(1 "F.Mask" user "Board Geometry/Soldermask Top")
		(3 "B.Mask" user "Board Geometry/Soldermask Bottom")
		(17 "Dwgs.User" user "User.Drawings")
		(19 "Cmts.User" user "User.Comments")
		(21 "Eco1.User" user "User.Eco1")
		(23 "Eco2.User" user "User.Eco2")
		(25 "Edge.Cuts" user "Board Geometry/Outline")
		(27 "Margin" user)
		(31 "F.CrtYd" user "Package Geometry/Place Bound Top")
		(29 "B.CrtYd" user "Package Geometry/Place Bound Bottom")
		(35 "F.Fab" user "Ref Des/Assembly Top")
		(33 "B.Fab" user "Ref Des/Assembly Bottom")
	)
	(footprint ""
		(layer "F.Cu")
		(at 168.6306 -105.029 -90)
		(property "Reference" "C462"
			(at 0 0 270)
			(layer "F.SilkS")
			(hide yes)
			(effects
				(font
					(size 1.27 1.27)
				)
			)
		)
		(property "Value" "SC1U16V2KX-7-GP"
			(at 1.7526 -1.6002 270)
			(unlocked yes)
			(layer "F.Fab")
			(hide yes)
			(effects
				(font
					(size 1.016 1.016)
					(thickness 0.1524)
				)
			)
		)
		(property "Device Type" "C402-TO0D2H24"
			(at 1.7526 -3.1242 270)
			(unlocked yes)
			(layer "F.Fab")
			(hide yes)
			(effects
				(font
					(size 1.016 1.016)
					(thickness 0.1524)
				)
			)
		)
		(duplicate_pad_numbers_are_jumpers no)
		(fp_rect
			(start -0.4826 0.889)
			(end 0.4826 -0.889)
			(stroke
				(width 0)
				(type default)
			)
			(fill no)
			(layer "F.CrtYd")
		)
		(fp_rect
			(start -0.4826 0.889)
			(end 0.4826 -0.889)
			(stroke
				(width 0)
				(type default)
			)
			(fill no)
			(layer "F.Fab")
		)
		(pad "1" smd custom
			(at 0 -0.4572 270)
			(size 0.1524 0.1524)
			(layers "F.Cu" "F.Mask" "F.Paste")
			(net "P1V8")
			(options
				(clearance outline)
				(anchor circle)
			)
			(primitives
				(gr_poly
					(pts
						(arc
							(start -0.254 0.3048)
							(mid -0.325842 0.275042)
							(end -0.3556 0.2032)
						)
						(arc
							(start -0.3556 -0.2032)
							(mid -0.325842 -0.275042)
							(end -0.254 -0.3048)
						)
						(arc
							(start 0.254 -0.3048)
							(mid 0.325842 -0.275042)
							(end 0.3556 -0.2032)
						)
						(arc
							(start 0.3556 0.2032)
							(mid 0.325842 0.275042)
							(end 0.254 0.3048)
						)
					)
					(width 0)
					(fill yes)
				)
			)
		)
		(pad "2" smd custom
			(at 0 0.4572 270)
			(size 0.1524 0.1524)
			(layers "F.Cu" "F.Mask" "F.Paste")
			(net "GND")
			(options
				(clearance outline)
				(anchor circle)
			)
			(primitives
				(gr_poly
					(pts
						(arc
							(start -0.254 0.3048)
							(mid -0.325842 0.275042)
							(end -0.3556 0.2032)
						)
						(arc
							(start -0.3556 -0.2032)
							(mid -0.325842 -0.275042)
							(end -0.254 -0.3048)
						)
						(arc
							(start 0.254 -0.3048)
							(mid 0.325842 -0.275042)
							(end 0.3556 -0.2032)
						)
						(arc
							(start 0.3556 0.2032)
							(mid 0.325842 0.275042)
							(end 0.254 0.3048)
						)
					)
					(width 0)
					(fill yes)
				)
			)
		)
	)
	(footprint ""
		(layer "F.Cu")
		(at 171.831 -124.333 -90)
		(property "Reference" "Q7"
			(at 0 0 270)
			(layer "F.SilkS")
			(hide yes)
			(effects
				(font
					(size 1.27 1.27)
				)
			)
		)
		(property "Value" "2N7002K-1-GP"
			(at 0.127 -8.9662 270)
			(unlocked yes)
			(layer "F.Fab")
			(hide yes)
			(effects
				(font
					(size 1.016 1.016)
					(thickness 0.1524)
				)
			)
		)
		(property "Device Type" "SOT23DGS2D4H44"
			(at 0.127 -10.4902 270)
			(unlocked yes)
			(layer "F.Fab")
			(hide yes)
			(effects
				(font
					(size 1.016 1.016)
					(thickness 0.1524)
				)
			)
		)
		(duplicate_pad_numbers_are_jumpers no)
		(fp_line
			(start -1.651 1.778)
			(end 1.651 1.778)
			(stroke
				(width 0.1524)
				(type default)
			)
			(layer "F.SilkS")
		)
		(fp_line
			(start 1.651 1.778)
			(end 1.651 -1.778)
			(stroke
				(width 0.1524)
				(type default)
			)
			(layer "F.SilkS")
		)
		(fp_line
			(start -1.651 -1.778)
			(end -1.651 1.778)
			(stroke
				(width 0.1524)
				(type default)
			)
			(layer "F.SilkS")
		)
		(fp_line
			(start 1.651 -1.778)
			(end -1.651 -1.778)
			(stroke
				(width 0.1524)
				(type default)
			)
			(layer "F.SilkS")
		)
		(fp_poly
			(pts
				(xy -1.778 1.8796) (xy -1.778 -1.8796) (xy 1.778 -1.8796) (xy 1.778 1.8796)
			)
			(stroke
				(width 0)
				(type default)
			)
			(fill no)
			(layer "F.CrtYd")
		)
		(fp_poly
			(pts
				(xy -1.778 1.8796) (xy -1.778 -1.8796) (xy 1.778 -1.8796) (xy 1.778 1.8796)
			)
			(stroke
				(width 0)
				(type default)
			)
			(fill no)
			(layer "F.Fab")
		)
		(pad "D" smd custom
			(at 0 -0.9525 270)
			(size 0.1905 0.1905)
			(layers "F.Cu" "F.Mask" "F.Paste")
			(net "Q6_G")
			(options
				(clearance outline)
				(anchor circle)
			)
			(primitives
				(gr_poly
					(pts
						(arc
							(start -0.1778 0.5715)
							(mid -0.321484 0.511984)
							(end -0.381 0.3683)
						)
						(arc
							(start -0.381 -0.3683)
							(mid -0.321484 -0.511984)
							(end -0.1778 -0.5715)
						)
						(arc
							(start 0.1778 -0.5715)
							(mid 0.321484 -0.511984)
							(end 0.381 -0.3683)
						)
						(arc
							(start 0.381 0.3683)
							(mid 0.321484 0.511984)
							(end 0.1778 0.5715)
						)
					)
					(width 0)
					(fill yes)
				)
			)
		)
		(pad "G" smd custom
			(at -0.98425 0.9525 270)
			(size 0.1905 0.1905)
			(layers "F.Cu" "F.Mask" "F.Paste")
			(net "Q7_G")
			(options
				(clearance outline)
				(anchor circle)
			)
			(primitives
				(gr_poly
					(pts
						(arc
							(start -0.1778 0.5715)
							(mid -0.321484 0.511984)
							(end -0.381 0.3683)
						)
						(arc
							(start -0.381 -0.3683)
							(mid -0.321484 -0.511984)
							(end -0.1778 -0.5715)
						)
						(arc
							(start 0.1778 -0.5715)
							(mid 0.321484 -0.511984)
							(end 0.381 -0.3683)
						)
						(arc
							(start 0.381 0.3683)
							(mid 0.321484 0.511984)
							(end 0.1778 0.5715)
						)
					)
					(width 0)
					(fill yes)
				)
			)
		)
		(pad "S" smd custom
			(at 0.98425 0.9525 270)
			(size 0.1905 0.1905)
			(layers "F.Cu" "F.Mask" "F.Paste")
			(net "GND")
			(options
				(clearance outline)
				(anchor circle)
			)
			(primitives
				(gr_poly
					(pts
						(arc
							(start -0.1778 0.5715)
							(mid -0.321484 0.511984)
							(end -0.381 0.3683)
						)
						(arc
							(start -0.381 -0.3683)
							(mid -0.321484 -0.511984)
							(end -0.1778 -0.5715)
						)
						(arc
							(start 0.1778 -0.5715)
							(mid 0.321484 -0.511984)
							(end 0.381 -0.3683)
						)
						(arc
							(start 0.381 0.3683)
							(mid 0.321484 0.511984)
							(end 0.1778 0.5715)
						)
					)
					(width 0)
					(fill yes)
				)
			)
		)
	)
	(footprint ""
		(layer "F.Cu")
		(at 49.022 -128.1938 180)
		(property "Reference" "R287"
			(at 0 0 180)
			(layer "F.SilkS")
			(hide yes)
			(effects
				(font
					(size 1.27 1.27)
				)
			)
		)
		(property "Value" "0R2J-2-GP"
			(at 0.064008 -3.993896 180)
			(unlocked yes)
			(layer "F.Fab")
			(hide yes)
			(effects
				(font
					(size 1.016 1.016)
					(thickness 0.1524)
				)
			)
		)
		(property "Device Type" "R402H16"
			(at 0.064008 -5.517896 180)
			(unlocked yes)
			(layer "F.Fab")
			(hide yes)
			(effects
				(font
					(size 1.016 1.016)
					(thickness 0.1524)
				)
			)
		)
		(duplicate_pad_numbers_are_jumpers no)
		(fp_line
			(start 0.508 -0.9398)
			(end -0.508 -0.9398)
			(stroke
				(width 0.1524)
				(type default)
			)
			(layer "F.SilkS")
		)
		(fp_line
			(start -0.508 -0.9398)
			(end -0.508 0.9398)
			(stroke
				(width 0.1524)
				(type default)
			)
			(layer "F.SilkS")
		)
		(fp_rect
			(start -0.508 0.9398)
			(end 0.508 -0.9398)
			(stroke
				(width 0)
				(type default)
			)
			(fill no)
			(layer "F.CrtYd")
		)
		(fp_rect
			(start -0.508 0.9398)
			(end 0.508 -0.9398)
			(stroke
				(width 0)
				(type default)
			)
			(fill no)
			(layer "F.Fab")
		)
		(pad "1" smd custom
			(at 0 -0.4445 180)
			(size 0.1397 0.1397)
			(layers "F.Cu" "F.Mask" "F.Paste")
			(net "SCC_RMT_FULL_PWR_EN")
			(options
				(clearance outline)
				(anchor circle)
			)
			(primitives
				(gr_poly
					(pts
						(arc
							(start -0.1778 -0.2794)
							(mid -0.249642 -0.249642)
							(end -0.2794 -0.1778)
						)
						(arc
							(start -0.2794 0.1778)
							(mid -0.249642 0.249642)
							(end -0.1778 0.2794)
						)
						(arc
							(start 0.1778 0.2794)
							(mid 0.249642 0.249642)
							(end 0.2794 0.1778)
						)
						(arc
							(start 0.2794 -0.1778)
							(mid 0.249642 -0.249642)
							(end 0.1778 -0.2794)
						)
					)
					(width 0)
					(fill yes)
				)
			)
		)
		(pad "2" smd custom
			(at 0 0.4445 180)
			(size 0.1397 0.1397)
			(layers "F.Cu" "F.Mask" "F.Paste")
			(net "SCC_RMT_FULLPWR_EN")
			(options
				(clearance outline)
				(anchor circle)
			)
			(primitives
				(gr_poly
					(pts
						(arc
							(start -0.1778 -0.2794)
							(mid -0.249642 -0.249642)
							(end -0.2794 -0.1778)
						)
						(arc
							(start -0.2794 0.1778)
							(mid -0.249642 0.249642)
							(end -0.1778 0.2794)
						)
						(arc
							(start 0.1778 0.2794)
							(mid 0.249642 0.249642)
							(end 0.2794 0.1778)
						)
						(arc
							(start 0.2794 -0.1778)
							(mid 0.249642 -0.249642)
							(end 0.1778 -0.2794)
						)
					)
					(width 0)
					(fill yes)
				)
			)
		)
	)
	(footprint ""
		(layer "F.Cu")
		(at 10.796524 -138.144504 90)
		(property "Reference" "R230"
			(at 0 0 90)
			(layer "F.SilkS")
			(hide yes)
			(effects
				(font
					(size 1.27 1.27)
				)
			)
		)
		(property "Value" "120R2F-GP"
			(at 0.064008 -3.993896 90)
			(unlocked yes)
			(layer "F.Fab")
			(hide yes)
			(effects
				(font
					(size 1.016 1.016)
					(thickness 0.1524)
				)
			)
		)
		(property "Device Type" "R402H16"
			(at 0.064008 -5.517896 90)
			(unlocked yes)
			(layer "F.Fab")
			(hide yes)
			(effects
				(font
					(size 1.016 1.016)
					(thickness 0.1524)
				)
			)
		)
		(duplicate_pad_numbers_are_jumpers no)
		(fp_line
			(start 0.508 -0.9398)
			(end -0.508 -0.9398)
			(stroke
				(width 0.1524)
				(type default)
			)
			(layer "F.SilkS")
		)
		(fp_line
			(start -0.508 -0.9398)
			(end -0.508 0.9398)
			(stroke
				(width 0.1524)
				(type default)
			)
			(layer "F.SilkS")
		)
		(fp_rect
			(start -0.508 0.9398)
			(end 0.508 -0.9398)
			(stroke
				(width 0)
				(type default)
			)
			(fill no)
			(layer "F.CrtYd")
		)
		(fp_rect
			(start -0.508 0.9398)
			(end 0.508 -0.9398)
			(stroke
				(width 0)
				(type default)
			)
			(fill no)
			(layer "F.Fab")
		)
		(pad "1" smd custom
			(at 0 -0.4445 90)
			(size 0.1397 0.1397)
			(layers "F.Cu" "F.Mask" "F.Paste")
			(net "MEMBA_0")
			(options
				(clearance outline)
				(anchor circle)
			)
			(primitives
				(gr_poly
					(pts
						(arc
							(start -0.1778 -0.2794)
							(mid -0.249642 -0.249642)
							(end -0.2794 -0.1778)
						)
						(arc
							(start -0.2794 0.1778)
							(mid -0.249642 0.249642)
							(end -0.1778 0.2794)
						)
						(arc
							(start 0.1778 0.2794)
							(mid 0.249642 0.249642)
							(end 0.2794 0.1778)
						)
						(arc
							(start 0.2794 -0.1778)
							(mid 0.249642 -0.249642)
							(end 0.1778 -0.2794)
						)
					)
					(width 0)
					(fill yes)
				)
			)
		)
		(pad "2" smd custom
			(at 0 0.4445 90)
			(size 0.1397 0.1397)
			(layers "F.Cu" "F.Mask" "F.Paste")
			(net "P1V2_STBY")
			(options
				(clearance outline)
				(anchor circle)
			)
			(primitives
				(gr_poly
					(pts
						(arc
							(start -0.1778 -0.2794)
							(mid -0.249642 -0.249642)
							(end -0.2794 -0.1778)
						)
						(arc
							(start -0.2794 0.1778)
							(mid -0.249642 0.249642)
							(end -0.1778 0.2794)
						)
						(arc
							(start 0.1778 0.2794)
							(mid 0.249642 0.249642)
							(end 0.2794 0.1778)
						)
						(arc
							(start 0.2794 -0.1778)
							(mid 0.249642 -0.249642)
							(end 0.1778 -0.2794)
						)
					)
					(width 0)
					(fill yes)
				)
			)
		)
	)
	(footprint ""
		(layer "F.Cu")
		(at 11.5824 -167.8178 90)
		(property "Reference" "C228"
			(at 0 0 90)
			(layer "F.SilkS")
			(hide yes)
			(effects
				(font
					(size 1.27 1.27)
				)
			)
		)
		(property "Value" "SC470P50V2KX-3GP"
			(at 1.1811 -2.7051 90)
			(unlocked yes)
			(layer "F.Fab")
			(hide yes)
			(effects
				(font
					(size 1.016 1.016)
					(thickness 0.1524)
				)
			)
		)
		(property "Device Type" "C402H22"
			(at 1.1811 -4.2291 90)
			(unlocked yes)
			(layer "F.Fab")
			(hide yes)
			(effects
				(font
					(size 1.016 1.016)
					(thickness 0.1524)
				)
			)
		)
		(duplicate_pad_numbers_are_jumpers no)
		(fp_rect
			(start -0.4318 0.9525)
			(end 0.4318 -0.9525)
			(stroke
				(width 0)
				(type default)
			)
			(fill no)
			(layer "F.CrtYd")
		)
		(fp_rect
			(start -0.4318 0.9525)
			(end 0.4318 -0.9525)
			(stroke
				(width 0)
				(type default)
			)
			(fill no)
			(layer "F.Fab")
		)
		(pad "1" smd custom
			(at 0 -0.4445 90)
			(size 0.1524 0.1524)
			(layers "F.Cu" "F.Mask" "F.Paste")
			(net "GND")
			(options
				(clearance outline)
				(anchor circle)
			)
			(primitives
				(gr_poly
					(pts
						(arc
							(start 0.3048 -0.2032)
							(mid 0.275042 -0.275042)
							(end 0.2032 -0.3048)
						)
						(arc
							(start -0.2032 -0.3048)
							(mid -0.275042 -0.275042)
							(end -0.3048 -0.2032)
						)
						(arc
							(start -0.3048 0.2032)
							(mid -0.275042 0.275042)
							(end -0.2032 0.3048)
						)
						(arc
							(start 0.2032 0.3048)
							(mid 0.275042 0.275042)
							(end 0.3048 0.2032)
						)
					)
					(width 0)
					(fill yes)
				)
			)
		)
		(pad "2" smd custom
			(at 0 0.4445 90)
			(size 0.1524 0.1524)
			(layers "F.Cu" "F.Mask" "F.Paste")
			(net "TPS74801_P1V2_STBY_SS")
			(options
				(clearance outline)
				(anchor circle)
			)
			(primitives
				(gr_poly
					(pts
						(arc
							(start 0.3048 -0.2032)
							(mid 0.275042 -0.275042)
							(end 0.2032 -0.3048)
						)
						(arc
							(start -0.2032 -0.3048)
							(mid -0.275042 -0.275042)
							(end -0.3048 -0.2032)
						)
						(arc
							(start -0.3048 0.2032)
							(mid -0.275042 0.275042)
							(end -0.2032 0.3048)
						)
						(arc
							(start 0.2032 0.3048)
							(mid 0.275042 0.275042)
							(end 0.3048 0.2032)
						)
					)
					(width 0)
					(fill yes)
				)
			)
		)
	)
	(footprint ""
		(layer "F.Cu")
		(at 88.647016 -46.05782 180)
		(property "Reference" "R10"
			(at 0 0 180)
			(layer "F.SilkS")
			(hide yes)
			(effects
				(font
					(size 1.27 1.27)
				)
			)
		)
		(property "Value" "0R2J-2-GP"
			(at 0.064008 -3.993896 180)
			(unlocked yes)
			(layer "F.Fab")
			(hide yes)
			(effects
				(font
					(size 1.016 1.016)
					(thickness 0.1524)
				)
			)
		)
		(property "Device Type" "R402H16"
			(at 0.064008 -5.517896 180)
			(unlocked yes)
			(layer "F.Fab")
			(hide yes)
			(effects
				(font
					(size 1.016 1.016)
					(thickness 0.1524)
				)
			)
		)
		(duplicate_pad_numbers_are_jumpers no)
		(fp_line
			(start 0.508 -0.9398)
			(end -0.508 -0.9398)
			(stroke
				(width 0.1524)
				(type default)
			)
			(layer "F.SilkS")
		)
		(fp_line
			(start -0.508 -0.9398)
			(end -0.508 0.9398)
			(stroke
				(width 0.1524)
				(type default)
			)
			(layer "F.SilkS")
		)
		(fp_rect
			(start -0.508 0.9398)
			(end 0.508 -0.9398)
			(stroke
				(width 0)
				(type default)
			)
			(fill no)
			(layer "F.CrtYd")
		)
		(fp_rect
			(start -0.508 0.9398)
			(end 0.508 -0.9398)
			(stroke
				(width 0)
				(type default)
			)
			(fill no)
			(layer "F.Fab")
		)
		(pad "1" smd custom
			(at 0 -0.4445 180)
			(size 0.1397 0.1397)
			(layers "F.Cu" "F.Mask" "F.Paste")
			(net "MEZZA_PRSNT1_N")
			(options
				(clearance outline)
				(anchor circle)
			)
			(primitives
				(gr_poly
					(pts
						(arc
							(start -0.1778 -0.2794)
							(mid -0.249642 -0.249642)
							(end -0.2794 -0.1778)
						)
						(arc
							(start -0.2794 0.1778)
							(mid -0.249642 0.249642)
							(end -0.1778 0.2794)
						)
						(arc
							(start 0.1778 0.2794)
							(mid 0.249642 0.249642)
							(end 0.2794 0.1778)
						)
						(arc
							(start 0.2794 -0.1778)
							(mid 0.249642 -0.249642)
							(end 0.1778 -0.2794)
						)
					)
					(width 0)
					(fill yes)
				)
			)
		)
		(pad "2" smd custom
			(at 0 0.4445 180)
			(size 0.1397 0.1397)
			(layers "F.Cu" "F.Mask" "F.Paste")
			(net "GND")
			(options
				(clearance outline)
				(anchor circle)
			)
			(primitives
				(gr_poly
					(pts
						(arc
							(start -0.1778 -0.2794)
							(mid -0.249642 -0.249642)
							(end -0.2794 -0.1778)
						)
						(arc
							(start -0.2794 0.1778)
							(mid -0.249642 0.249642)
							(end -0.1778 0.2794)
						)
						(arc
							(start 0.1778 0.2794)
							(mid 0.249642 0.249642)
							(end 0.2794 0.1778)
						)
						(arc
							(start 0.2794 -0.1778)
							(mid 0.249642 -0.249642)
							(end 0.1778 -0.2794)
						)
					)
					(width 0)
					(fill yes)
				)
			)
		)
	)
	(footprint ""
		(layer "F.Cu")
		(at 32.6898 -134.6962 90)
		(property "Reference" "R369"
			(at 0 0 90)
			(layer "F.SilkS")
			(hide yes)
			(effects
				(font
					(size 1.27 1.27)
				)
			)
		)
		(property "Value" "4K7R2F-GP"
			(at 0.064008 -3.993896 90)
			(unlocked yes)
			(layer "F.Fab")
			(hide yes)
			(effects
				(font
					(size 1.016 1.016)
					(thickness 0.1524)
				)
			)
		)
		(property "Device Type" "R402H16"
			(at 0.064008 -5.517896 90)
			(unlocked yes)
			(layer "F.Fab")
			(hide yes)
			(effects
				(font
					(size 1.016 1.016)
					(thickness 0.1524)
				)
			)
		)
		(duplicate_pad_numbers_are_jumpers no)
		(fp_line
			(start 0.508 -0.9398)
			(end -0.508 -0.9398)
			(stroke
				(width 0.1524)
				(type default)
			)
			(layer "F.SilkS")
		)
		(fp_line
			(start -0.508 -0.9398)
			(end -0.508 0.9398)
			(stroke
				(width 0.1524)
				(type default)
			)
			(layer "F.SilkS")
		)
		(fp_rect
			(start -0.508 0.9398)
			(end 0.508 -0.9398)
			(stroke
				(width 0)
				(type default)
			)
			(fill no)
			(layer "F.CrtYd")
		)
		(fp_rect
			(start -0.508 0.9398)
			(end 0.508 -0.9398)
			(stroke
				(width 0)
				(type default)
			)
			(fill no)
			(layer "F.Fab")
		)
		(pad "1" smd custom
			(at 0 -0.4445 90)
			(size 0.1397 0.1397)
			(layers "F.Cu" "F.Mask" "F.Paste")
			(net "P3V3_STBY")
			(options
				(clearance outline)
				(anchor circle)
			)
			(primitives
				(gr_poly
					(pts
						(arc
							(start -0.1778 -0.2794)
							(mid -0.249642 -0.249642)
							(end -0.2794 -0.1778)
						)
						(arc
							(start -0.2794 0.1778)
							(mid -0.249642 0.249642)
							(end -0.1778 0.2794)
						)
						(arc
							(start 0.1778 0.2794)
							(mid 0.249642 0.249642)
							(end 0.2794 0.1778)
						)
						(arc
							(start 0.2794 -0.1778)
							(mid 0.249642 -0.249642)
							(end 0.1778 -0.2794)
						)
					)
					(width 0)
					(fill yes)
				)
			)
		)
		(pad "2" smd custom
			(at 0 0.4445 90)
			(size 0.1397 0.1397)
			(layers "F.Cu" "F.Mask" "F.Paste")
			(net "BMC_SPI_CLK")
			(options
				(clearance outline)
				(anchor circle)
			)
			(primitives
				(gr_poly
					(pts
						(arc
							(start -0.1778 -0.2794)
							(mid -0.249642 -0.249642)
							(end -0.2794 -0.1778)
						)
						(arc
							(start -0.2794 0.1778)
							(mid -0.249642 0.249642)
							(end -0.1778 0.2794)
						)
						(arc
							(start 0.1778 0.2794)
							(mid 0.249642 0.249642)
							(end 0.2794 0.1778)
						)
						(arc
							(start 0.2794 -0.1778)
							(mid 0.249642 -0.249642)
							(end 0.1778 -0.2794)
						)
					)
					(width 0)
					(fill yes)
				)
			)
		)
	)
)
